(kicad_pcb
	(version 20260206)
	(generator "pcbnew")
	(generator_version "10.0")
	(general
		(thickness 1.6)
		(legacy_teardrops no)
	)
	(paper "A4")
	(title_block
		(title "01162023_DA0F0TEBIF0_F0T_Expander_BD_F_brd_V02_OCP.brd")
		(comment 1 "Grand Teton / footprints 3779-3786 of 9728")
	)
	(layers
		(0 "F.Cu" signal "TOP")
		(4 "In1.Cu" signal "GND")
		(6 "In2.Cu" signal "VCC")
		(8 "In3.Cu" signal "VCC1")
		(10 "In4.Cu" signal "GND1")
		(12 "In5.Cu" signal "IN1")
		(14 "In6.Cu" signal "GND2")
		(16 "In7.Cu" signal "IN2")
		(18 "In8.Cu" signal "GND3")
		(20 "In9.Cu" signal "IN3")
		(22 "In10.Cu" signal "GND4")
		(24 "In11.Cu" signal "IN4")
		(26 "In12.Cu" signal "GND5")
		(28 "In13.Cu" signal "IN5")
		(30 "In14.Cu" signal "GND6")
		(32 "In15.Cu" signal "IN6")
		(34 "In16.Cu" signal "GND7")
		(2 "B.Cu" signal "BOTTOM")
		(9 "F.Adhes" user "F.Adhesive")
		(11 "B.Adhes" user "B.Adhesive")
		(13 "F.Paste" user "Package Geometry/Pastemask Top")
		(15 "B.Paste" user "Package Geometry/Pastemask Bottom")
		(5 "F.SilkS" user "Ref Des/Silkscreen Top")
		(7 "B.SilkS" user "Ref Des/Silkscreen Bottom")
		(1 "F.Mask" user "Board Geometry/Soldermask Top")
		(3 "B.Mask" user "Board Geometry/Soldermask Bottom")
		(17 "Dwgs.User" user "User.Drawings")
		(19 "Cmts.User" user "User.Comments")
		(21 "Eco1.User" user "User.Eco1")
		(23 "Eco2.User" user "User.Eco2")
		(25 "Edge.Cuts" user "Board Geometry/Outline")
		(27 "Margin" user)
		(31 "F.CrtYd" user "Package Geometry/Place Bound Top")
		(29 "B.CrtYd" user "Package Geometry/Place Bound Bottom")
		(35 "F.Fab" user "Ref Des/Assembly Top")
		(33 "B.Fab" user "Ref Des/Assembly Bottom")
	)
	(footprint ""
		(layer "F.Cu")
		(at 359.385362 -115.549426 -90)
		(property "Reference" "Q218"
			(at -0.071374 1.853692 90)
			(unlocked yes)
			(layer "F.SilkS")
			(effects
				(font
					(size 0.7874 0.5842)
					(thickness 0.1524)
				)
			)
		)
		(property "Value" ""
			(at 0 0 270)
			(layer "F.Fab")
			(effects
				(font
					(size 1.27 1.27)
				)
			)
		)
		(duplicate_pad_numbers_are_jumpers no)
		(fp_line
			(start -1.376172 1.199896)
			(end -1.376172 -1.199896)
			(stroke
				(width 0.1524)
				(type default)
			)
			(layer "F.SilkS")
		)
		(fp_line
			(start 1.376172 1.199896)
			(end -1.376172 1.199896)
			(stroke
				(width 0.1524)
				(type default)
			)
			(layer "F.SilkS")
		)
		(fp_line
			(start 0 -0.762)
			(end 0.508 -1.199896)
			(stroke
				(width 0.1524)
				(type default)
			)
			(layer "F.SilkS")
		)
		(fp_line
			(start -1.376172 -1.199896)
			(end -0.508 -1.199896)
			(stroke
				(width 0.1524)
				(type default)
			)
			(layer "F.SilkS")
		)
		(fp_line
			(start -0.508 -1.199896)
			(end 0 -0.762)
			(stroke
				(width 0.1524)
				(type default)
			)
			(layer "F.SilkS")
		)
		(fp_line
			(start 0.508 -1.199896)
			(end 1.376172 -1.199896)
			(stroke
				(width 0.1524)
				(type default)
			)
			(layer "F.SilkS")
		)
		(fp_line
			(start 1.376172 -1.199896)
			(end 1.376172 1.199896)
			(stroke
				(width 0.1524)
				(type default)
			)
			(layer "F.SilkS")
		)
		(fp_poly
			(pts
				(xy -1.175004 -1.325372) (xy -1.444498 -2.1336) (xy -1.983232 -1.594866)
			)
			(stroke
				(width 0)
				(type default)
			)
			(fill yes)
			(layer "F.SilkS")
		)
		(fp_line
			(start -0.674878 1.100074)
			(end -0.674878 -1.100074)
			(stroke
				(width 0.1)
				(type default)
			)
			(layer "F.Fab")
		)
		(fp_line
			(start 0.674878 1.100074)
			(end -0.674878 1.100074)
			(stroke
				(width 0.1)
				(type default)
			)
			(layer "F.Fab")
		)
		(fp_line
			(start -0.674878 -1.100074)
			(end 0.674878 -1.100074)
			(stroke
				(width 0.1)
				(type default)
			)
			(layer "F.Fab")
		)
		(fp_line
			(start 0.674878 -1.100074)
			(end 0.674878 1.100074)
			(stroke
				(width 0.1)
				(type default)
			)
			(layer "F.Fab")
		)
		(fp_poly
			(pts
				(xy -1.4605 -0.7493) (xy -2.2225 -1.1303) (xy -2.2225 -0.3683)
			)
			(stroke
				(width 0)
				(type default)
			)
			(fill yes)
			(layer "F.Fab")
		)
		(pad "1" smd rect
			(at -0.899922 -0.750062 180)
			(size 0.6096 0.6096)
			(layers "F.Cu" "F.Mask" "F.Paste")
			(net "GND")
		)
		(pad "2" smd rect
			(at -0.899922 0 180)
			(size 0.4064 0.6096)
			(layers "F.Cu" "F.Mask" "F.Paste")
			(net "P3V3_NIC6_PG_G1")
		)
		(pad "3" smd rect
			(at -0.899922 0.750062 180)
			(size 0.6096 0.6096)
			(layers "F.Cu" "F.Mask" "F.Paste")
			(net "PWRGD_P3V3_NIC6_D")
		)
		(pad "4" smd rect
			(at 0.899922 0.750062 180)
			(size 0.6096 0.6096)
			(layers "F.Cu" "F.Mask" "F.Paste")
			(net "GND")
		)
		(pad "5" smd rect
			(at 0.899922 0 180)
			(size 0.4064 0.6096)
			(layers "F.Cu" "F.Mask" "F.Paste")
			(net "P3V3_NIC6_PG_G2")
		)
		(pad "6" smd rect
			(at 0.899922 -0.750062 180)
			(size 0.6096 0.6096)
			(layers "F.Cu" "F.Mask" "F.Paste")
			(net "P3V3_NIC6_PG_G2")
		)
	)
	(footprint ""
		(layer "F.Cu")
		(at 262.638286 -252.356874 -90)
		(property "Reference" "R1356"
			(at 0 0 270)
			(layer "F.SilkS")
			(hide yes)
			(effects
				(font
					(size 1.27 1.27)
				)
			)
		)
		(property "Value" ""
			(at 0 0 270)
			(layer "F.Fab")
			(effects
				(font
					(size 1.27 1.27)
				)
			)
		)
		(duplicate_pad_numbers_are_jumpers no)
		(fp_line
			(start -0.7874 0.4064)
			(end -0.7874 -0.4064)
			(stroke
				(width 0.1524)
				(type default)
			)
			(layer "F.SilkS")
		)
		(fp_line
			(start 0.7874 0.4064)
			(end -0.7874 0.4064)
			(stroke
				(width 0.1524)
				(type default)
			)
			(layer "F.SilkS")
		)
		(fp_line
			(start -0.7874 -0.4064)
			(end 0.7874 -0.4064)
			(stroke
				(width 0.1524)
				(type default)
			)
			(layer "F.SilkS")
		)
		(fp_line
			(start 0.7874 -0.4064)
			(end 0.7874 0.4064)
			(stroke
				(width 0.1524)
				(type default)
			)
			(layer "F.SilkS")
		)
		(fp_line
			(start -0.67945 0.3048)
			(end -0.67945 -0.305054)
			(stroke
				(width 0.1)
				(type default)
			)
			(layer "F.Fab")
		)
		(fp_line
			(start -0.12065 0.3048)
			(end -0.67945 0.3048)
			(stroke
				(width 0.1)
				(type default)
			)
			(layer "F.Fab")
		)
		(fp_line
			(start 0.120396 0.3048)
			(end 0.120396 0.2794)
			(stroke
				(width 0.1)
				(type default)
			)
			(layer "F.Fab")
		)
		(fp_line
			(start 0.67945 0.3048)
			(end 0.120396 0.3048)
			(stroke
				(width 0.1)
				(type default)
			)
			(layer "F.Fab")
		)
		(fp_line
			(start -0.12065 0.2794)
			(end -0.12065 0.3048)
			(stroke
				(width 0.1)
				(type default)
			)
			(layer "F.Fab")
		)
		(fp_line
			(start 0.120396 0.2794)
			(end -0.12065 0.2794)
			(stroke
				(width 0.1)
				(type default)
			)
			(layer "F.Fab")
		)
		(fp_line
			(start -0.12065 -0.2794)
			(end 0.12065 -0.2794)
			(stroke
				(width 0.1)
				(type default)
			)
			(layer "F.Fab")
		)
		(fp_line
			(start 0.12065 -0.2794)
			(end 0.12065 -0.3048)
			(stroke
				(width 0.1)
				(type default)
			)
			(layer "F.Fab")
		)
		(fp_line
			(start 0.12065 -0.3048)
			(end 0.67945 -0.3048)
			(stroke
				(width 0.1)
				(type default)
			)
			(layer "F.Fab")
		)
		(fp_line
			(start 0.67945 -0.3048)
			(end 0.67945 0.3048)
			(stroke
				(width 0.1)
				(type default)
			)
			(layer "F.Fab")
		)
		(fp_line
			(start -0.67945 -0.305054)
			(end -0.12065 -0.305054)
			(stroke
				(width 0.1)
				(type default)
			)
			(layer "F.Fab")
		)
		(fp_line
			(start -0.12065 -0.305054)
			(end -0.12065 -0.2794)
			(stroke
				(width 0.1)
				(type default)
			)
			(layer "F.Fab")
		)
		(pad "1" smd circle
			(at -0.40005 0 270)
			(size 0 0)
			(layers "F.Cu" "F.Mask" "F.Paste")
			(net "GND")
		)
		(pad "2" smd circle
			(at 0.40005 0 270)
			(size 0 0)
			(layers "F.Cu" "F.Mask" "F.Paste")
			(net "PEX2_MODE_SEL0")
		)
	)
	(footprint ""
		(layer "F.Cu")
		(at 268.838426 -131.323334)
		(property "Reference" "C462"
			(at 0 0 0)
			(layer "F.SilkS")
			(hide yes)
			(effects
				(font
					(size 1.27 1.27)
				)
			)
		)
		(property "Value" ""
			(at 0 0 0)
			(layer "F.Fab")
			(effects
				(font
					(size 1.27 1.27)
				)
			)
		)
		(duplicate_pad_numbers_are_jumpers no)
		(fp_line
			(start -0.299974 -0.150114)
			(end 0.299974 -0.150114)
			(stroke
				(width 0.1)
				(type default)
			)
			(layer "F.Fab")
		)
		(fp_line
			(start -0.299974 0.150114)
			(end -0.299974 -0.150114)
			(stroke
				(width 0.1)
				(type default)
			)
			(layer "F.Fab")
		)
		(fp_line
			(start 0.299974 -0.150114)
			(end 0.299974 0.150114)
			(stroke
				(width 0.1)
				(type default)
			)
			(layer "F.Fab")
		)
		(fp_line
			(start 0.299974 0.150114)
			(end -0.299974 0.150114)
			(stroke
				(width 0.1)
				(type default)
			)
			(layer "F.Fab")
		)
		(pad "1" smd rect
			(at -0.2667 0)
			(size 0.3048 0.381)
			(layers "F.Cu" "F.Mask" "F.Paste")
			(net "P5E_PEX2_STN1_TX_DN<28>")
		)
		(pad "2" smd rect
			(at 0.2667 0)
			(size 0.3048 0.381)
			(layers "F.Cu" "F.Mask" "F.Paste")
			(net "P5E_PEX2_STN1_TX_C_DN<28>")
		)
	)
	(footprint ""
		(layer "F.Cu")
		(at 20.434554 -33.631886 180)
		(property "Reference" "C66"
			(at 0 0 180)
			(layer "F.SilkS")
			(hide yes)
			(effects
				(font
					(size 1.27 1.27)
				)
			)
		)
		(property "Value" ""
			(at 0 0 180)
			(layer "F.Fab")
			(effects
				(font
					(size 1.27 1.27)
				)
			)
		)
		(duplicate_pad_numbers_are_jumpers no)
		(fp_line
			(start 0.299974 0.150114)
			(end -0.299974 0.150114)
			(stroke
				(width 0.1)
				(type default)
			)
			(layer "F.Fab")
		)
		(fp_line
			(start 0.299974 -0.150114)
			(end 0.299974 0.150114)
			(stroke
				(width 0.1)
				(type default)
			)
			(layer "F.Fab")
		)
		(fp_line
			(start -0.299974 0.150114)
			(end -0.299974 -0.150114)
			(stroke
				(width 0.1)
				(type default)
			)
			(layer "F.Fab")
		)
		(fp_line
			(start -0.299974 -0.150114)
			(end 0.299974 -0.150114)
			(stroke
				(width 0.1)
				(type default)
			)
			(layer "F.Fab")
		)
		(pad "1" smd rect
			(at -0.2667 0 180)
			(size 0.3048 0.381)
			(layers "F.Cu" "F.Mask" "F.Paste")
			(net "P5E_PEX0_STN2_TX_DN<47>")
		)
		(pad "2" smd rect
			(at 0.2667 0 180)
			(size 0.3048 0.381)
			(layers "F.Cu" "F.Mask" "F.Paste")
			(net "P5E_PEX0_STN2_TX_C_DN<47>")
		)
	)
	(footprint ""
		(layer "F.Cu")
		(at 395.247368 -20.35556)
		(property "Reference" "C3968"
			(at 0 0 0)
			(layer "F.SilkS")
			(hide yes)
			(effects
				(font
					(size 1.27 1.27)
				)
			)
		)
		(property "Value" ""
			(at 0 0 0)
			(layer "F.Fab")
			(effects
				(font
					(size 1.27 1.27)
				)
			)
		)
		(duplicate_pad_numbers_are_jumpers no)
		(fp_line
			(start -0.7874 -0.4064)
			(end 0.7874 -0.4064)
			(stroke
				(width 0.1524)
				(type default)
			)
			(layer "F.SilkS")
		)
		(fp_line
			(start -0.7874 0.4064)
			(end -0.7874 -0.4064)
			(stroke
				(width 0.1524)
				(type default)
			)
			(layer "F.SilkS")
		)
		(fp_line
			(start 0.7874 -0.4064)
			(end 0.7874 0.4064)
			(stroke
				(width 0.1524)
				(type default)
			)
			(layer "F.SilkS")
		)
		(fp_line
			(start 0.7874 0.4064)
			(end -0.7874 0.4064)
			(stroke
				(width 0.1524)
				(type default)
			)
			(layer "F.SilkS")
		)
		(fp_line
			(start -0.67945 -0.305054)
			(end -0.12065 -0.305054)
			(stroke
				(width 0.1)
				(type default)
			)
			(layer "F.Fab")
		)
		(fp_line
			(start -0.67945 0.3048)
			(end -0.67945 -0.305054)
			(stroke
				(width 0.1)
				(type default)
			)
			(layer "F.Fab")
		)
		(fp_line
			(start -0.12065 -0.305054)
			(end -0.12065 -0.2794)
			(stroke
				(width 0.1)
				(type default)
			)
			(layer "F.Fab")
		)
		(fp_line
			(start -0.12065 -0.2794)
			(end 0.12065 -0.2794)
			(stroke
				(width 0.1)
				(type default)
			)
			(layer "F.Fab")
		)
		(fp_line
			(start -0.12065 0.2794)
			(end -0.12065 0.3048)
			(stroke
				(width 0.1)
				(type default)
			)
			(layer "F.Fab")
		)
		(fp_line
			(start -0.12065 0.3048)
			(end -0.67945 0.3048)
			(stroke
				(width 0.1)
				(type default)
			)
			(layer "F.Fab")
		)
		(fp_line
			(start 0.120396 0.2794)
			(end -0.12065 0.2794)
			(stroke
				(width 0.1)
				(type default)
			)
			(layer "F.Fab")
		)
		(fp_line
			(start 0.120396 0.3048)
			(end 0.120396 0.2794)
			(stroke
				(width 0.1)
				(type default)
			)
			(layer "F.Fab")
		)
		(fp_line
			(start 0.12065 -0.3048)
			(end 0.67945 -0.3048)
			(stroke
				(width 0.1)
				(type default)
			)
			(layer "F.Fab")
		)
		(fp_line
			(start 0.12065 -0.2794)
			(end 0.12065 -0.3048)
			(stroke
				(width 0.1)
				(type default)
			)
			(layer "F.Fab")
		)
		(fp_line
			(start 0.67945 -0.3048)
			(end 0.67945 0.3048)
			(stroke
				(width 0.1)
				(type default)
			)
			(layer "F.Fab")
		)
		(fp_line
			(start 0.67945 0.3048)
			(end 0.120396 0.3048)
			(stroke
				(width 0.1)
				(type default)
			)
			(layer "F.Fab")
		)
		(pad "1" smd circle
			(at -0.40005 0)
			(size 0 0)
			(layers "F.Cu" "F.Mask" "F.Paste")
			(net "P12V_SSD13")
		)
		(pad "2" smd circle
			(at 0.40005 0)
			(size 0 0)
			(layers "F.Cu" "F.Mask" "F.Paste")
			(net "GND")
		)
	)
	(footprint ""
		(layer "F.Cu")
		(at 314.072016 -32.848042 90)
		(property "Reference" "PC952"
			(at 0 0 90)
			(layer "F.SilkS")
			(hide yes)
			(effects
				(font
					(size 1.27 1.27)
				)
			)
		)
		(property "Value" ""
			(at 0 0 90)
			(layer "F.Fab")
			(effects
				(font
					(size 1.27 1.27)
				)
			)
		)
		(duplicate_pad_numbers_are_jumpers no)
		(fp_line
			(start 0.7874 -0.4064)
			(end 0.7874 0.4064)
			(stroke
				(width 0.1524)
				(type default)
			)
			(layer "F.SilkS")
		)
		(fp_line
			(start -0.7874 -0.4064)
			(end 0.7874 -0.4064)
			(stroke
				(width 0.1524)
				(type default)
			)
			(layer "F.SilkS")
		)
		(fp_line
			(start 0.7874 0.4064)
			(end -0.7874 0.4064)
			(stroke
				(width 0.1524)
				(type default)
			)
			(layer "F.SilkS")
		)
		(fp_line
			(start -0.7874 0.4064)
			(end -0.7874 -0.4064)
			(stroke
				(width 0.1524)
				(type default)
			)
			(layer "F.SilkS")
		)
		(fp_line
			(start -0.12065 -0.305054)
			(end -0.12065 -0.2794)
			(stroke
				(width 0.1)
				(type default)
			)
			(layer "F.Fab")
		)
		(fp_line
			(start -0.67945 -0.305054)
			(end -0.12065 -0.305054)
			(stroke
				(width 0.1)
				(type default)
			)
			(layer "F.Fab")
		)
		(fp_line
			(start 0.67945 -0.3048)
			(end 0.67945 0.3048)
			(stroke
				(width 0.1)
				(type default)
			)
			(layer "F.Fab")
		)
		(fp_line
			(start 0.12065 -0.3048)
			(end 0.67945 -0.3048)
			(stroke
				(width 0.1)
				(type default)
			)
			(layer "F.Fab")
		)
		(fp_line
			(start 0.12065 -0.2794)
			(end 0.12065 -0.3048)
			(stroke
				(width 0.1)
				(type default)
			)
			(layer "F.Fab")
		)
		(fp_line
			(start -0.12065 -0.2794)
			(end 0.12065 -0.2794)
			(stroke
				(width 0.1)
				(type default)
			)
			(layer "F.Fab")
		)
		(fp_line
			(start 0.120396 0.2794)
			(end -0.12065 0.2794)
			(stroke
				(width 0.1)
				(type default)
			)
			(layer "F.Fab")
		)
		(fp_line
			(start -0.12065 0.2794)
			(end -0.12065 0.3048)
			(stroke
				(width 0.1)
				(type default)
			)
			(layer "F.Fab")
		)
		(fp_line
			(start 0.67945 0.3048)
			(end 0.120396 0.3048)
			(stroke
				(width 0.1)
				(type default)
			)
			(layer "F.Fab")
		)
		(fp_line
			(start 0.120396 0.3048)
			(end 0.120396 0.2794)
			(stroke
				(width 0.1)
				(type default)
			)
			(layer "F.Fab")
		)
		(fp_line
			(start -0.12065 0.3048)
			(end -0.67945 0.3048)
			(stroke
				(width 0.1)
				(type default)
			)
			(layer "F.Fab")
		)
		(fp_line
			(start -0.67945 0.3048)
			(end -0.67945 -0.305054)
			(stroke
				(width 0.1)
				(type default)
			)
			(layer "F.Fab")
		)
		(pad "1" smd circle
			(at -0.40005 0 90)
			(size 0 0)
			(layers "F.Cu" "F.Mask" "F.Paste")
			(net "P3V3_SSD11_CO_GATE")
		)
		(pad "2" smd circle
			(at 0.40005 0 90)
			(size 0 0)
			(layers "F.Cu" "F.Mask" "F.Paste")
			(net "GND")
		)
	)
	(footprint ""
		(layer "F.Cu")
		(at 32.411416 -293.245032 -90)
		(property "Reference" "R4560"
			(at 0 0 270)
			(layer "F.SilkS")
			(hide yes)
			(effects
				(font
					(size 1.27 1.27)
				)
			)
		)
		(property "Value" ""
			(at 0 0 270)
			(layer "F.Fab")
			(effects
				(font
					(size 1.27 1.27)
				)
			)
		)
		(duplicate_pad_numbers_are_jumpers no)
		(fp_line
			(start -0.7874 0.4064)
			(end -0.7874 -0.4064)
			(stroke
				(width 0.1524)
				(type default)
			)
			(layer "F.SilkS")
		)
		(fp_line
			(start 0.7874 0.4064)
			(end -0.7874 0.4064)
			(stroke
				(width 0.1524)
				(type default)
			)
			(layer "F.SilkS")
		)
		(fp_line
			(start -0.7874 -0.4064)
			(end 0.7874 -0.4064)
			(stroke
				(width 0.1524)
				(type default)
			)
			(layer "F.SilkS")
		)
		(fp_line
			(start 0.7874 -0.4064)
			(end 0.7874 0.4064)
			(stroke
				(width 0.1524)
				(type default)
			)
			(layer "F.SilkS")
		)
		(fp_line
			(start -0.67945 0.3048)
			(end -0.67945 -0.305054)
			(stroke
				(width 0.1)
				(type default)
			)
			(layer "F.Fab")
		)
		(fp_line
			(start -0.12065 0.3048)
			(end -0.67945 0.3048)
			(stroke
				(width 0.1)
				(type default)
			)
			(layer "F.Fab")
		)
		(fp_line
			(start 0.120396 0.3048)
			(end 0.120396 0.2794)
			(stroke
				(width 0.1)
				(type default)
			)
			(layer "F.Fab")
		)
		(fp_line
			(start 0.67945 0.3048)
			(end 0.120396 0.3048)
			(stroke
				(width 0.1)
				(type default)
			)
			(layer "F.Fab")
		)
		(fp_line
			(start -0.12065 0.2794)
			(end -0.12065 0.3048)
			(stroke
				(width 0.1)
				(type default)
			)
			(layer "F.Fab")
		)
		(fp_line
			(start 0.120396 0.2794)
			(end -0.12065 0.2794)
			(stroke
				(width 0.1)
				(type default)
			)
			(layer "F.Fab")
		)
		(fp_line
			(start -0.12065 -0.2794)
			(end 0.12065 -0.2794)
			(stroke
				(width 0.1)
				(type default)
			)
			(layer "F.Fab")
		)
		(fp_line
			(start 0.12065 -0.2794)
			(end 0.12065 -0.3048)
			(stroke
				(width 0.1)
				(type default)
			)
			(layer "F.Fab")
		)
		(fp_line
			(start 0.12065 -0.3048)
			(end 0.67945 -0.3048)
			(stroke
				(width 0.1)
				(type default)
			)
			(layer "F.Fab")
		)
		(fp_line
			(start 0.67945 -0.3048)
			(end 0.67945 0.3048)
			(stroke
				(width 0.1)
				(type default)
			)
			(layer "F.Fab")
		)
		(fp_line
			(start -0.67945 -0.305054)
			(end -0.12065 -0.305054)
			(stroke
				(width 0.1)
				(type default)
			)
			(layer "F.Fab")
		)
		(fp_line
			(start -0.12065 -0.305054)
			(end -0.12065 -0.2794)
			(stroke
				(width 0.1)
				(type default)
			)
			(layer "F.Fab")
		)
		(pad "1" smd circle
			(at -0.40005 0 270)
			(size 0 0)
			(layers "F.Cu" "F.Mask" "F.Paste")
			(net "PCEPLL2_VDDA18_PEX0")
		)
		(pad "2" smd circle
			(at 0.40005 0 270)
			(size 0 0)
			(layers "F.Cu" "F.Mask" "F.Paste")
			(net "PCEPLL2_VDDA18_PEX0_R")
		)
	)
	(footprint ""
		(layer "F.Cu")
		(at 196.119242 -130.794506 180)
		(property "Reference" "C234"
			(at 0 0 180)
			(layer "F.SilkS")
			(hide yes)
			(effects
				(font
					(size 1.27 1.27)
				)
			)
		)
		(property "Value" ""
			(at 0 0 180)
			(layer "F.Fab")
			(effects
				(font
					(size 1.27 1.27)
				)
			)
		)
		(duplicate_pad_numbers_are_jumpers no)
		(fp_line
			(start 0.299974 0.150114)
			(end -0.299974 0.150114)
			(stroke
				(width 0.1)
				(type default)
			)
			(layer "F.Fab")
		)
		(fp_line
			(start 0.299974 -0.150114)
			(end 0.299974 0.150114)
			(stroke
				(width 0.1)
				(type default)
			)
			(layer "F.Fab")
		)
		(fp_line
			(start -0.299974 0.150114)
			(end -0.299974 -0.150114)
			(stroke
				(width 0.1)
				(type default)
			)
			(layer "F.Fab")
		)
		(fp_line
			(start -0.299974 -0.150114)
			(end 0.299974 -0.150114)
			(stroke
				(width 0.1)
				(type default)
			)
			(layer "F.Fab")
		)
		(pad "1" smd rect
			(at -0.2667 0 180)
			(size 0.3048 0.381)
			(layers "F.Cu" "F.Mask" "F.Paste")
			(net "P5E_PEX1_STN0_TX_DP<4>")
		)
		(pad "2" smd rect
			(at 0.2667 0 180)
			(size 0.3048 0.381)
			(layers "F.Cu" "F.Mask" "F.Paste")
			(net "P5E_PEX1_STN0_TX_C_DP<4>")
		)
	)
)
